(kicad_pcb
	(version 20241229)
	(generator "pcbnew")
	(generator_version "9.0")
	(general
		(thickness 1.61)
		(legacy_teardrops no)
	)
	(paper "A3")
	(title_block
		(title "SO-DIMM DDR5 Tester")
		(date "2025-11-26")
		(rev "1.3.0")
		(comment 9 "footprints 407-411 of 627")
	)
	(layers
		(0 "F.Cu" signal)
		(4 "In1.Cu" power)
		(6 "In2.Cu" mixed)
		(8 "In3.Cu" power)
		(10 "In4.Cu" mixed)
		(12 "In5.Cu" power)
		(14 "In6.Cu" mixed)
		(16 "In7.Cu" power)
		(18 "In8.Cu" power)
		(20 "In9.Cu" mixed)
		(22 "In10.Cu" power)
		(2 "B.Cu" signal)
		(9 "F.Adhes" user "F.Adhesive")
		(11 "B.Adhes" user "B.Adhesive")
		(13 "F.Paste" user)
		(15 "B.Paste" user)
		(5 "F.SilkS" user "F.Silkscreen")
		(7 "B.SilkS" user "B.Silkscreen")
		(1 "F.Mask" user)
		(3 "B.Mask" user)
		(17 "Dwgs.User" user "User.Drawings")
		(19 "Cmts.User" user "User.Comments")
		(21 "Eco1.User" user "User.Eco1")
		(23 "Eco2.User" user "User.Eco2")
		(25 "Edge.Cuts" user)
		(27 "Margin" user)
		(31 "F.CrtYd" user "F.Courtyard")
		(29 "B.CrtYd" user "B.Courtyard")
		(35 "F.Fab" user)
		(33 "B.Fab" user)
	)
	(footprint "antmicro-footprints:C_0402_1005Metric"
		(layer "B.Cu")
		(at 149.377001 183.8005 -90)
		(descr "Capacitor SMD 0402 (1005 Metric), square (rectangular) end terminal, IPC_7351 nominal, (Body size source: IPC-SM-782 page 76, https://www.pcb-3d.com/wordpress/wp-content/uploads/ipc-sm-782a_amendment_1_and_2.pdf)")
		(tags "capacitor 0402")
		(property "Reference" "C108"
			(at 0 1.17 90)
			(layer "B.SilkS")
			(hide yes)
			(effects
				(font
					(size 0.7 0.7)
					(thickness 0.15)
				)
				(justify left bottom mirror)
			)
		)
		(property "Value" "C_100n_0402"
			(at 0 -1.169 90)
			(layer "B.Fab")
			(effects
				(font
					(size 0.7 0.7)
					(thickness 0.15)
				)
				(justify left bottom mirror)
			)
		)
		(property "Datasheet" "https://www.murata.com/products/productdetail?partno=GRM155R61H104KE14%23"
			(at 0 0 270)
			(layer "F.Fab")
			(hide yes)
			(effects
				(font
					(size 1.27 1.27)
					(thickness 0.15)
				)
			)
		)
		(property "Author" "Antmicro"
			(at -34.423499 333.177501 0)
			(layer "B.Fab")
			(hide yes)
			(effects
				(font
					(size 1 1)
					(thickness 0.15)
				)
				(justify mirror)
			)
		)
		(property "Dielectric" "X5R"
			(at -34.423499 333.177501 0)
			(layer "B.Fab")
			(hide yes)
			(effects
				(font
					(size 1 1)
					(thickness 0.15)
				)
				(justify mirror)
			)
		)
		(property "License" "Apache-2.0"
			(at -34.423499 333.177501 0)
			(layer "B.Fab")
			(hide yes)
			(effects
				(font
					(size 1 1)
					(thickness 0.15)
				)
				(justify mirror)
			)
		)
		(property "MPN" "GRM155R61H104KE14D"
			(at -34.423499 333.177501 0)
			(layer "B.Fab")
			(hide yes)
			(effects
				(font
					(size 1 1)
					(thickness 0.15)
				)
				(justify mirror)
			)
		)
		(property "Manufacturer" "Murata"
			(at -34.423499 333.177501 0)
			(layer "B.Fab")
			(hide yes)
			(effects
				(font
					(size 1 1)
					(thickness 0.15)
				)
				(justify mirror)
			)
		)
		(property "Val" "100n"
			(at -34.423499 333.177501 0)
			(layer "B.Fab")
			(hide yes)
			(effects
				(font
					(size 1 1)
					(thickness 0.15)
				)
				(justify mirror)
			)
		)
		(property "Voltage" "50V"
			(at -34.423499 333.177501 0)
			(layer "B.Fab")
			(hide yes)
			(effects
				(font
					(size 1 1)
					(thickness 0.15)
				)
				(justify mirror)
			)
		)
		(sheetname "/FPGA power/")
		(sheetfile "fpga-power.kicad_sch")
		(attr smd)
		(fp_rect
			(start -0.9656 0.4572)
			(end 0.9652 -0.4828)
			(stroke
				(width 0.05)
				(type solid)
			)
			(fill no)
			(layer "B.CrtYd")
		)
		(fp_line
			(start -0.5 0.25)
			(end 0.498 0.25)
			(stroke
				(width 0.15)
				(type solid)
			)
			(layer "B.Fab")
		)
		(fp_line
			(start 0.498 0.25)
			(end 0.498 -0.248)
			(stroke
				(width 0.15)
				(type solid)
			)
			(layer "B.Fab")
		)
		(fp_line
			(start -0.5 -0.248)
			(end -0.5 0.25)
			(stroke
				(width 0.15)
				(type solid)
			)
			(layer "B.Fab")
		)
		(fp_line
			(start 0.498 -0.248)
			(end -0.5 -0.248)
			(stroke
				(width 0.15)
				(type solid)
			)
			(layer "B.Fab")
		)
		(pad "1" smd roundrect
			(at -0.5 0 180)
			(size 0.6 0.6)
			(layers "B.Cu" "B.Mask" "B.Paste")
			(roundrect_rratio 0.25)
			(net 1 "GND")
			(pintype "passive")
		)
		(pad "2" smd roundrect
			(at 0.498 0 270)
			(size 0.6 0.6)
			(layers "B.Cu" "B.Mask" "B.Paste")
			(roundrect_rratio 0.25)
			(net 226 "+1V2_MGTAVTT")
			(pintype "passive")
		)
	)
	(footprint "antmicro-footprints:C_0603_1608Metric"
		(layer "B.Cu")
		(at 138.900501 185.276 90)
		(descr "Capacitor SMD 0603")
		(tags "capacitor 0603")
		(property "Reference" "C16"
			(at 0 0.9 90)
			(layer "B.SilkS")
			(hide yes)
			(effects
				(font
					(size 0.7 0.7)
					(thickness 0.15)
				)
				(justify right bottom mirror)
			)
		)
		(property "Value" "C_47u_0603"
			(at 0 -1.6 90)
			(layer "B.Fab")
			(effects
				(font
					(size 0.7 0.7)
					(thickness 0.15)
				)
				(justify right bottom mirror)
			)
		)
		(property "Datasheet" "https://www.murata.com/products/productdetail?partno=GRM188R60J476ME15%23"
			(at 0 0 90)
			(layer "F.Fab")
			(hide yes)
			(effects
				(font
					(size 1.27 1.27)
					(thickness 0.15)
				)
			)
		)
		(property "Author" "Antmicro"
			(at 324.176501 46.375499 0)
			(layer "B.Fab")
			(hide yes)
			(effects
				(font
					(size 1 1)
					(thickness 0.15)
				)
				(justify mirror)
			)
		)
		(property "Dielectric" ""
			(at 324.176501 46.375499 0)
			(layer "B.Fab")
			(hide yes)
			(effects
				(font
					(size 1 1)
					(thickness 0.15)
				)
				(justify mirror)
			)
		)
		(property "License" "Apache-2.0"
			(at 324.176501 46.375499 0)
			(layer "B.Fab")
			(hide yes)
			(effects
				(font
					(size 1 1)
					(thickness 0.15)
				)
				(justify mirror)
			)
		)
		(property "MPN" "GRM188R60J476ME15D"
			(at 324.176501 46.375499 0)
			(layer "B.Fab")
			(hide yes)
			(effects
				(font
					(size 1 1)
					(thickness 0.15)
				)
				(justify mirror)
			)
		)
		(property "Manufacturer" "Murata"
			(at 324.176501 46.375499 0)
			(layer "B.Fab")
			(hide yes)
			(effects
				(font
					(size 1 1)
					(thickness 0.15)
				)
				(justify mirror)
			)
		)
		(property "Val" "47u"
			(at 324.176501 46.375499 0)
			(layer "B.Fab")
			(hide yes)
			(effects
				(font
					(size 1 1)
					(thickness 0.15)
				)
				(justify mirror)
			)
		)
		(property "Voltage" ""
			(at 324.176501 46.375499 0)
			(layer "B.Fab")
			(hide yes)
			(effects
				(font
					(size 1 1)
					(thickness 0.15)
				)
				(justify mirror)
			)
		)
		(sheetname "/FPGA power/")
		(sheetfile "fpga-power.kicad_sch")
		(attr smd)
		(fp_line
			(start -0.3 -0.3)
			(end 0.3 -0.3)
			(stroke
				(width 0.15)
				(type solid)
			)
			(layer "B.SilkS")
		)
		(fp_line
			(start -0.3 0.3)
			(end 0.3 0.3)
			(stroke
				(width 0.15)
				(type solid)
			)
			(layer "B.SilkS")
		)
		(fp_rect
			(start -1.24 0.7)
			(end 1.24 -0.7)
			(stroke
				(width 0.05)
				(type solid)
			)
			(fill no)
			(layer "B.CrtYd")
		)
		(fp_rect
			(start -0.8 0.4)
			(end 0.8 -0.4)
			(stroke
				(width 0.15)
				(type solid)
			)
			(fill no)
			(layer "B.Fab")
		)
		(pad "1" smd roundrect
			(at -0.7 0 90)
			(size 0.6 0.8)
			(layers "B.Cu" "B.Mask" "B.Paste")
			(roundrect_rratio 0.2)
			(net 200 "+3V3")
			(pintype "passive")
		)
		(pad "2" smd roundrect
			(at 0.7 0 90)
			(size 0.6 0.8)
			(layers "B.Cu" "B.Mask" "B.Paste")
			(roundrect_rratio 0.2)
			(net 1 "GND")
			(pintype "passive")
		)
	)
	(footprint "antmicro-footprints:C_0402_1005Metric"
		(layer "B.Cu")
		(at 133.875501 163.301 180)
		(descr "Capacitor SMD 0402 (1005 Metric), square (rectangular) end terminal, IPC_7351 nominal, (Body size source: IPC-SM-782 page 76, https://www.pcb-3d.com/wordpress/wp-content/uploads/ipc-sm-782a_amendment_1_and_2.pdf)")
		(tags "capacitor 0402")
		(property "Reference" "C20"
			(at 0 1.17 0)
			(layer "B.SilkS")
			(hide yes)
			(effects
				(font
					(size 0.7 0.7)
					(thickness 0.15)
				)
				(justify left bottom mirror)
			)
		)
		(property "Value" "C_100n_0402"
			(at 0 -1.169 0)
			(layer "B.Fab")
			(effects
				(font
					(size 0.7 0.7)
					(thickness 0.15)
				)
				(justify left bottom mirror)
			)
		)
		(property "Datasheet" "https://www.murata.com/products/productdetail?partno=GRM155R61H104KE14%23"
			(at 0 0 180)
			(layer "F.Fab")
			(hide yes)
			(effects
				(font
					(size 1.27 1.27)
					(thickness 0.15)
				)
			)
		)
		(property "Author" "Antmicro"
			(at 267.751002 326.602 0)
			(layer "B.Fab")
			(hide yes)
			(effects
				(font
					(size 1 1)
					(thickness 0.15)
				)
				(justify mirror)
			)
		)
		(property "Dielectric" "X5R"
			(at 267.751002 326.602 0)
			(layer "B.Fab")
			(hide yes)
			(effects
				(font
					(size 1 1)
					(thickness 0.15)
				)
				(justify mirror)
			)
		)
		(property "License" "Apache-2.0"
			(at 267.751002 326.602 0)
			(layer "B.Fab")
			(hide yes)
			(effects
				(font
					(size 1 1)
					(thickness 0.15)
				)
				(justify mirror)
			)
		)
		(property "MPN" "GRM155R61H104KE14D"
			(at 267.751002 326.602 0)
			(layer "B.Fab")
			(hide yes)
			(effects
				(font
					(size 1 1)
					(thickness 0.15)
				)
				(justify mirror)
			)
		)
		(property "Manufacturer" "Murata"
			(at 267.751002 326.602 0)
			(layer "B.Fab")
			(hide yes)
			(effects
				(font
					(size 1 1)
					(thickness 0.15)
				)
				(justify mirror)
			)
		)
		(property "Val" "100n"
			(at 267.751002 326.602 0)
			(layer "B.Fab")
			(hide yes)
			(effects
				(font
					(size 1 1)
					(thickness 0.15)
				)
				(justify mirror)
			)
		)
		(property "Voltage" "50V"
			(at 267.751002 326.602 0)
			(layer "B.Fab")
			(hide yes)
			(effects
				(font
					(size 1 1)
					(thickness 0.15)
				)
				(justify mirror)
			)
		)
		(sheetname "/FPGA power/")
		(sheetfile "fpga-power.kicad_sch")
		(attr smd)
		(fp_rect
			(start -0.9656 0.4572)
			(end 0.9652 -0.4828)
			(stroke
				(width 0.05)
				(type solid)
			)
			(fill no)
			(layer "B.CrtYd")
		)
		(fp_line
			(start 0.498 0.25)
			(end 0.498 -0.248)
			(stroke
				(width 0.15)
				(type solid)
			)
			(layer "B.Fab")
		)
		(fp_line
			(start 0.498 -0.248)
			(end -0.5 -0.248)
			(stroke
				(width 0.15)
				(type solid)
			)
			(layer "B.Fab")
		)
		(fp_line
			(start -0.5 0.25)
			(end 0.498 0.25)
			(stroke
				(width 0.15)
				(type solid)
			)
			(layer "B.Fab")
		)
		(fp_line
			(start -0.5 -0.248)
			(end -0.5 0.25)
			(stroke
				(width 0.15)
				(type solid)
			)
			(layer "B.Fab")
		)
		(pad "1" smd roundrect
			(at -0.5 0 90)
			(size 0.6 0.6)
			(layers "B.Cu" "B.Mask" "B.Paste")
			(roundrect_rratio 0.25)
			(net 1 "GND")
			(pintype "passive")
		)
		(pad "2" smd roundrect
			(at 0.498 0 180)
			(size 0.6 0.6)
			(layers "B.Cu" "B.Mask" "B.Paste")
			(roundrect_rratio 0.25)
			(net 206 "+1V1")
			(pintype "passive")
		)
	)
	(footprint "antmicro-footprints:C_0402_1005Metric"
		(layer "B.Cu")
		(at 139.375001 178.8025 90)
		(descr "Capacitor SMD 0402 (1005 Metric), square (rectangular) end terminal, IPC_7351 nominal, (Body size source: IPC-SM-782 page 76, https://www.pcb-3d.com/wordpress/wp-content/uploads/ipc-sm-782a_amendment_1_and_2.pdf)")
		(tags "capacitor 0402")
		(property "Reference" "C79"
			(at 0 1.17 270)
			(layer "B.SilkS")
			(hide yes)
			(effects
				(font
					(size 0.7 0.7)
					(thickness 0.15)
				)
				(justify left bottom mirror)
			)
		)
		(property "Value" "C_100n_0402"
			(at 0 -1.169 270)
			(layer "B.Fab")
			(effects
				(font
					(size 0.7 0.7)
					(thickness 0.15)
				)
				(justify left bottom mirror)
			)
		)
		(property "Datasheet" "https://www.murata.com/products/productdetail?partno=GRM155R61H104KE14%23"
			(at 0 0 90)
			(layer "F.Fab")
			(hide yes)
			(effects
				(font
					(size 1.27 1.27)
					(thickness 0.15)
				)
			)
		)
		(property "Author" "Antmicro"
			(at 318.177501 39.427499 0)
			(layer "B.Fab")
			(hide yes)
			(effects
				(font
					(size 1 1)
					(thickness 0.15)
				)
				(justify mirror)
			)
		)
		(property "Dielectric" "X5R"
			(at 318.177501 39.427499 0)
			(layer "B.Fab")
			(hide yes)
			(effects
				(font
					(size 1 1)
					(thickness 0.15)
				)
				(justify mirror)
			)
		)
		(property "License" "Apache-2.0"
			(at 318.177501 39.427499 0)
			(layer "B.Fab")
			(hide yes)
			(effects
				(font
					(size 1 1)
					(thickness 0.15)
				)
				(justify mirror)
			)
		)
		(property "MPN" "GRM155R61H104KE14D"
			(at 318.177501 39.427499 0)
			(layer "B.Fab")
			(hide yes)
			(effects
				(font
					(size 1 1)
					(thickness 0.15)
				)
				(justify mirror)
			)
		)
		(property "Manufacturer" "Murata"
			(at 318.177501 39.427499 0)
			(layer "B.Fab")
			(hide yes)
			(effects
				(font
					(size 1 1)
					(thickness 0.15)
				)
				(justify mirror)
			)
		)
		(property "Val" "100n"
			(at 318.177501 39.427499 0)
			(layer "B.Fab")
			(hide yes)
			(effects
				(font
					(size 1 1)
					(thickness 0.15)
				)
				(justify mirror)
			)
		)
		(property "Voltage" "50V"
			(at 318.177501 39.427499 0)
			(layer "B.Fab")
			(hide yes)
			(effects
				(font
					(size 1 1)
					(thickness 0.15)
				)
				(justify mirror)
			)
		)
		(sheetname "/FPGA power/")
		(sheetfile "fpga-power.kicad_sch")
		(attr smd)
		(fp_rect
			(start -0.9656 0.4572)
			(end 0.9652 -0.4828)
			(stroke
				(width 0.05)
				(type solid)
			)
			(fill no)
			(layer "B.CrtYd")
		)
		(fp_line
			(start 0.498 -0.248)
			(end -0.5 -0.248)
			(stroke
				(width 0.15)
				(type solid)
			)
			(layer "B.Fab")
		)
		(fp_line
			(start -0.5 -0.248)
			(end -0.5 0.25)
			(stroke
				(width 0.15)
				(type solid)
			)
			(layer "B.Fab")
		)
		(fp_line
			(start 0.498 0.25)
			(end 0.498 -0.248)
			(stroke
				(width 0.15)
				(type solid)
			)
			(layer "B.Fab")
		)
		(fp_line
			(start -0.5 0.25)
			(end 0.498 0.25)
			(stroke
				(width 0.15)
				(type solid)
			)
			(layer "B.Fab")
		)
		(pad "1" smd roundrect
			(at -0.5 0)
			(size 0.6 0.6)
			(layers "B.Cu" "B.Mask" "B.Paste")
			(roundrect_rratio 0.25)
			(net 1 "GND")
			(pintype "passive")
		)
		(pad "2" smd roundrect
			(at 0.498 0 90)
			(size 0.6 0.6)
			(layers "B.Cu" "B.Mask" "B.Paste")
			(roundrect_rratio 0.25)
			(net 227 "+1V0")
			(pintype "passive")
		)
	)
	(footprint "antmicro-footprints:C_0402_1005Metric"
		(layer "B.Cu")
		(at 146.375001 185.800501 -90)
		(descr "Capacitor SMD 0402 (1005 Metric), square (rectangular) end terminal, IPC_7351 nominal, (Body size source: IPC-SM-782 page 76, https://www.pcb-3d.com/wordpress/wp-content/uploads/ipc-sm-782a_amendment_1_and_2.pdf)")
		(tags "capacitor 0402")
		(property "Reference" "C102"
			(at 0 1.17 90)
			(layer "B.SilkS")
			(hide yes)
			(effects
				(font
					(size 0.7 0.7)
					(thickness 0.15)
				)
				(justify left bottom mirror)
			)
		)
		(property "Value" "C_4u7_0402"
			(at 0 -1.169 90)
			(layer "B.Fab")
			(effects
				(font
					(size 0.7 0.7)
					(thickness 0.15)
				)
				(justify left bottom mirror)
			)
		)
		(property "Datasheet" "https://www.murata.com/products/productdetail?partno=GRM155R61A475MEAA%23"
			(at 0 0 270)
			(layer "F.Fab")
			(hide yes)
			(effects
				(font
					(size 1.27 1.27)
					(thickness 0.15)
				)
			)
		)
		(property "Author" "Antmicro"
			(at -39.4255 332.175502 0)
			(layer "B.Fab")
			(hide yes)
			(effects
				(font
					(size 1 1)
					(thickness 0.15)
				)
				(justify mirror)
			)
		)
		(property "Dielectric" ""
			(at -39.4255 332.175502 0)
			(layer "B.Fab")
			(hide yes)
			(effects
				(font
					(size 1 1)
					(thickness 0.15)
				)
				(justify mirror)
			)
		)
		(property "License" "Apache-2.0"
			(at -39.4255 332.175502 0)
			(layer "B.Fab")
			(hide yes)
			(effects
				(font
					(size 1 1)
					(thickness 0.15)
				)
				(justify mirror)
			)
		)
		(property "MPN" "GRM155R61A475MEAAD"
			(at -39.4255 332.175502 0)
			(layer "B.Fab")
			(hide yes)
			(effects
				(font
					(size 1 1)
					(thickness 0.15)
				)
				(justify mirror)
			)
		)
		(property "Manufacturer" "Murata"
			(at -39.4255 332.175502 0)
			(layer "B.Fab")
			(hide yes)
			(effects
				(font
					(size 1 1)
					(thickness 0.15)
				)
				(justify mirror)
			)
		)
		(property "Val" "4u7"
			(at -39.4255 332.175502 0)
			(layer "B.Fab")
			(hide yes)
			(effects
				(font
					(size 1 1)
					(thickness 0.15)
				)
				(justify mirror)
			)
		)
		(property "Voltage" ""
			(at -39.4255 332.175502 0)
			(layer "B.Fab")
			(hide yes)
			(effects
				(font
					(size 1 1)
					(thickness 0.15)
				)
				(justify mirror)
			)
		)
		(sheetname "/FPGA power/")
		(sheetfile "fpga-power.kicad_sch")
		(attr smd)
		(fp_rect
			(start -0.9656 0.4572)
			(end 0.9652 -0.4828)
			(stroke
				(width 0.05)
				(type solid)
			)
			(fill no)
			(layer "B.CrtYd")
		)
		(fp_line
			(start -0.5 0.25)
			(end 0.498 0.25)
			(stroke
				(width 0.15)
				(type solid)
			)
			(layer "B.Fab")
		)
		(fp_line
			(start 0.498 0.25)
			(end 0.498 -0.248)
			(stroke
				(width 0.15)
				(type solid)
			)
			(layer "B.Fab")
		)
		(fp_line
			(start -0.5 -0.248)
			(end -0.5 0.25)
			(stroke
				(width 0.15)
				(type solid)
			)
			(layer "B.Fab")
		)
		(fp_line
			(start 0.498 -0.248)
			(end -0.5 -0.248)
			(stroke
				(width 0.15)
				(type solid)
			)
			(layer "B.Fab")
		)
		(pad "1" smd roundrect
			(at -0.5 0 180)
			(size 0.6 0.6)
			(layers "B.Cu" "B.Mask" "B.Paste")
			(roundrect_rratio 0.25)
			(net 187 "+1V0_MGTAVCC")
			(pintype "passive")
		)
		(pad "2" smd roundrect
			(at 0.498 0 270)
			(size 0.6 0.6)
			(layers "B.Cu" "B.Mask" "B.Paste")
			(roundrect_rratio 0.25)
			(net 1 "GND")
			(pintype "passive")
		)
	)
)
